# T6G (Grand Teton) — schematic netlist excerpt (pin names and nets, part order shuffled) for the footprints in the layout excerpt that follows; sources: Cadence DE-HDL packaged netlist, KiCad conversion of 04192023_DAF0TMB3IC0_F0TG_MB_C_brd_V02_OCP.brd

PC271  Q_CAP  0.22UF 16V 10% X7R  pkg 0402  page 211 : A = SW_PVDDCR_CPU0_P1_BOOT2_RC ; B = SW_PVDDCR_CPU0_P1_PH2
PR6600  Q_RES  49.9 1% CHIP  pkg 0402LF  page 364 : A = P0V9_RETIMER_CPU1_SENSE_SH_P ; B = P0V9_CPU1_RT_2D

(kicad_pcb
	(version 20260206)
	(generator "pcbnew")
	(generator_version "10.0")
	(general
		(thickness 1.6)
		(legacy_teardrops no)
	)
	(paper "A4")
	(title_block
		(title "04192023_DAF0TMB3IC0_F0TG_MB_C_brd_V02_OCP.brd")
		(comment 1 "Grand Teton / footprints 4038-4039 of 8354")
	)
	(layers
		(0 "F.Cu" signal "TOP")
		(4 "In1.Cu" signal "GND")
		(6 "In2.Cu" signal "IN1")
		(8 "In3.Cu" signal "GND1")
		(10 "In4.Cu" signal "IN2")
		(12 "In5.Cu" signal "GND2")
		(14 "In6.Cu" signal "IN3")
		(16 "In7.Cu" signal "GND3")
		(18 "In8.Cu" signal "VCC")
		(20 "In9.Cu" signal "VCC1")
		(22 "In10.Cu" signal "GND4")
		(24 "In11.Cu" signal "IN4")
		(26 "In12.Cu" signal "GND5")
		(28 "In13.Cu" signal "IN5")
		(30 "In14.Cu" signal "GND6")
		(32 "In15.Cu" signal "IN6")
		(34 "In16.Cu" signal "GND7")
		(2 "B.Cu" signal "BOTTOM")
		(9 "F.Adhes" user "F.Adhesive")
		(11 "B.Adhes" user "B.Adhesive")
		(13 "F.Paste" user "Package Geometry/Pastemask Top")
		(15 "B.Paste" user "Package Geometry/Pastemask Bottom")
		(5 "F.SilkS" user "Ref Des/Silkscreen Top")
		(7 "B.SilkS" user "Ref Des/Silkscreen Bottom")
		(1 "F.Mask" user "Board Geometry/Soldermask Top")
		(3 "B.Mask" user "Board Geometry/Soldermask Bottom")
		(17 "Dwgs.User" user "User.Drawings")
		(19 "Cmts.User" user "User.Comments")
		(21 "Eco1.User" user "User.Eco1")
		(23 "Eco2.User" user "User.Eco2")
		(25 "Edge.Cuts" user "Board Geometry/Outline")
		(27 "Margin" user)
		(31 "F.CrtYd" user "Package Geometry/Place Bound Top")
		(29 "B.CrtYd" user "Package Geometry/Place Bound Bottom")
		(35 "F.Fab" user "Ref Des/Assembly Top")
		(33 "B.Fab" user "Ref Des/Assembly Bottom")
	)
	(footprint ""
		(layer "F.Cu")
		(at 8.406384 -380.470156)
		(property "Reference" "PR6600"
			(at 0 0 0)
			(layer "F.SilkS")
			(hide yes)
			(effects
				(font
					(size 1.27 1.27)
				)
			)
		)
		(property "Value" ""
			(at 0 0 0)
			(layer "F.Fab")
			(effects
				(font
					(size 1.27 1.27)
				)
			)
		)
		(duplicate_pad_numbers_are_jumpers no)
		(fp_line
			(start -0.7874 -0.4064)
			(end 0.7874 -0.4064)
			(stroke
				(width 0.1524)
				(type default)
			)
			(layer "F.SilkS")
		)
		(fp_line
			(start -0.7874 0.4064)
			(end -0.7874 -0.4064)
			(stroke
				(width 0.1524)
				(type default)
			)
			(layer "F.SilkS")
		)
		(fp_line
			(start 0.7874 -0.4064)
			(end 0.7874 0.4064)
			(stroke
				(width 0.1524)
				(type default)
			)
			(layer "F.SilkS")
		)
		(fp_line
			(start 0.7874 0.4064)
			(end -0.7874 0.4064)
			(stroke
				(width 0.1524)
				(type default)
			)
			(layer "F.SilkS")
		)
		(fp_line
			(start -0.67945 -0.305054)
			(end -0.12065 -0.305054)
			(stroke
				(width 0.1)
				(type default)
			)
			(layer "F.Fab")
		)
		(fp_line
			(start -0.67945 0.3048)
			(end -0.67945 -0.305054)
			(stroke
				(width 0.1)
				(type default)
			)
			(layer "F.Fab")
		)
		(fp_line
			(start -0.12065 -0.305054)
			(end -0.12065 -0.2794)
			(stroke
				(width 0.1)
				(type default)
			)
			(layer "F.Fab")
		)
		(fp_line
			(start -0.12065 -0.2794)
			(end 0.12065 -0.2794)
			(stroke
				(width 0.1)
				(type default)
			)
			(layer "F.Fab")
		)
		(fp_line
			(start -0.12065 0.2794)
			(end -0.12065 0.3048)
			(stroke
				(width 0.1)
				(type default)
			)
			(layer "F.Fab")
		)
		(fp_line
			(start -0.12065 0.3048)
			(end -0.67945 0.3048)
			(stroke
				(width 0.1)
				(type default)
			)
			(layer "F.Fab")
		)
		(fp_line
			(start 0.120396 0.2794)
			(end -0.12065 0.2794)
			(stroke
				(width 0.1)
				(type default)
			)
			(layer "F.Fab")
		)
		(fp_line
			(start 0.120396 0.3048)
			(end 0.120396 0.2794)
			(stroke
				(width 0.1)
				(type default)
			)
			(layer "F.Fab")
		)
		(fp_line
			(start 0.12065 -0.3048)
			(end 0.67945 -0.3048)
			(stroke
				(width 0.1)
				(type default)
			)
			(layer "F.Fab")
		)
		(fp_line
			(start 0.12065 -0.2794)
			(end 0.12065 -0.3048)
			(stroke
				(width 0.1)
				(type default)
			)
			(layer "F.Fab")
		)
		(fp_line
			(start 0.67945 -0.3048)
			(end 0.67945 0.3048)
			(stroke
				(width 0.1)
				(type default)
			)
			(layer "F.Fab")
		)
		(fp_line
			(start 0.67945 0.3048)
			(end 0.120396 0.3048)
			(stroke
				(width 0.1)
				(type default)
			)
			(layer "F.Fab")
		)
		(pad "1" smd circle
			(at -0.40005 0)
			(size 0 0)
			(layers "F.Cu" "F.Mask" "F.Paste")
			(net "P0V9_RETIMER_CPU1_SENSE_SH_P")
		)
		(pad "2" smd circle
			(at 0.40005 0)
			(size 0 0)
			(layers "F.Cu" "F.Mask" "F.Paste")
			(net "P0V9_CPU1_RT_2D")
		)
	)
	(footprint ""
		(layer "F.Cu")
		(at 88.895936 -178.024028 90)
		(property "Reference" "PC271"
			(at 0 0 90)
			(layer "F.SilkS")
			(hide yes)
			(effects
				(font
					(size 1.27 1.27)
				)
			)
		)
		(property "Value" ""
			(at 0 0 90)
			(layer "F.Fab")
			(effects
				(font
					(size 1.27 1.27)
				)
			)
		)
		(duplicate_pad_numbers_are_jumpers no)
		(fp_line
			(start 0.7874 -0.4064)
			(end 0.7874 0.4064)
			(stroke
				(width 0.1524)
				(type default)
			)
			(layer "F.SilkS")
		)
		(fp_line
			(start -0.7874 -0.4064)
			(end 0.7874 -0.4064)
			(stroke
				(width 0.1524)
				(type default)
			)
			(layer "F.SilkS")
		)
		(fp_line
			(start 0.7874 0.4064)
			(end -0.7874 0.4064)
			(stroke
				(width 0.1524)
				(type default)
			)
			(layer "F.SilkS")
		)
		(fp_line
			(start -0.7874 0.4064)
			(end -0.7874 -0.4064)
			(stroke
				(width 0.1524)
				(type default)
			)
			(layer "F.SilkS")
		)
		(fp_line
			(start -0.12065 -0.305054)
			(end -0.12065 -0.2794)
			(stroke
				(width 0.1)
				(type default)
			)
			(layer "F.Fab")
		)
		(fp_line
			(start -0.67945 -0.305054)
			(end -0.12065 -0.305054)
			(stroke
				(width 0.1)
				(type default)
			)
			(layer "F.Fab")
		)
		(fp_line
			(start 0.67945 -0.3048)
			(end 0.67945 0.3048)
			(stroke
				(width 0.1)
				(type default)
			)
			(layer "F.Fab")
		)
		(fp_line
			(start 0.12065 -0.3048)
			(end 0.67945 -0.3048)
			(stroke
				(width 0.1)
				(type default)
			)
			(layer "F.Fab")
		)
		(fp_line
			(start 0.12065 -0.2794)
			(end 0.12065 -0.3048)
			(stroke
				(width 0.1)
				(type default)
			)
			(layer "F.Fab")
		)
		(fp_line
			(start -0.12065 -0.2794)
			(end 0.12065 -0.2794)
			(stroke
				(width 0.1)
				(type default)
			)
			(layer "F.Fab")
		)
		(fp_line
			(start 0.120396 0.2794)
			(end -0.12065 0.2794)
			(stroke
				(width 0.1)
				(type default)
			)
			(layer "F.Fab")
		)
		(fp_line
			(start -0.12065 0.2794)
			(end -0.12065 0.3048)
			(stroke
				(width 0.1)
				(type default)
			)
			(layer "F.Fab")
		)
		(fp_line
			(start 0.67945 0.3048)
			(end 0.120396 0.3048)
			(stroke
				(width 0.1)
				(type default)
			)
			(layer "F.Fab")
		)
		(fp_line
			(start 0.120396 0.3048)
			(end 0.120396 0.2794)
			(stroke
				(width 0.1)
				(type default)
			)
			(layer "F.Fab")
		)
		(fp_line
			(start -0.12065 0.3048)
			(end -0.67945 0.3048)
			(stroke
				(width 0.1)
				(type default)
			)
			(layer "F.Fab")
		)
		(fp_line
			(start -0.67945 0.3048)
			(end -0.67945 -0.305054)
			(stroke
				(width 0.1)
				(type default)
			)
			(layer "F.Fab")
		)
		(pad "1" smd circle
			(at -0.40005 0 90)
			(size 0 0)
			(layers "F.Cu" "F.Mask" "F.Paste")
			(net "SW_PVDDCR_CPU0_P1_BOOT2_RC")
		)
		(pad "2" smd circle
			(at 0.40005 0 90)
			(size 0 0)
			(layers "F.Cu" "F.Mask" "F.Paste")
			(net "SW_PVDDCR_CPU0_P1_PH2")
		)
	)
)
